# T6G (Grand Teton) — schematic netlist excerpt (pin names and nets, part order shuffled) for the footprints in the layout excerpt that follows; sources: Cadence DE-HDL packaged netlist, KiCad conversion of 04192023_DAF0TMB3IC0_F0TG_MB_C_brd_V02_OCP.brd

PR294  Q_RES  49.9 1% CHIP  pkg 0402LF  page 193 : A = PVDDCR_CPU0_P0 ; B = VSENSE_PVDDCR_CPU0_P0_DP

U6003  M24128BWMN6TP  M24128-BWMN6TP IC  pkg SOIC8XH  page 176
  E0  = USB_CPU0_ADD_A0
  E1  = USB_CPU0_ADD_A1
  E2  = USB_CPU0_ADD_A2
  VSS  = GND
  SDA  = SMB_USB_CPU0_HUB1_SDA_R2
  SCL  = SMB_USB_CPU0_HUB1_SCL_R2
  \wc#\  = PD_USB_CPU0_WP
  VCC  = P3V3_AUX

(kicad_pcb
	(version 20260206)
	(generator "pcbnew")
	(generator_version "10.0")
	(general
		(thickness 1.6)
		(legacy_teardrops no)
	)
	(paper "A4")
	(title_block
		(title "04192023_DAF0TMB3IC0_F0TG_MB_C_brd_V02_OCP.brd")
		(comment 1 "Grand Teton / footprints 3497-3498 of 8354")
	)
	(layers
		(0 "F.Cu" signal "TOP")
		(4 "In1.Cu" signal "GND")
		(6 "In2.Cu" signal "IN1")
		(8 "In3.Cu" signal "GND1")
		(10 "In4.Cu" signal "IN2")
		(12 "In5.Cu" signal "GND2")
		(14 "In6.Cu" signal "IN3")
		(16 "In7.Cu" signal "GND3")
		(18 "In8.Cu" signal "VCC")
		(20 "In9.Cu" signal "VCC1")
		(22 "In10.Cu" signal "GND4")
		(24 "In11.Cu" signal "IN4")
		(26 "In12.Cu" signal "GND5")
		(28 "In13.Cu" signal "IN5")
		(30 "In14.Cu" signal "GND6")
		(32 "In15.Cu" signal "IN6")
		(34 "In16.Cu" signal "GND7")
		(2 "B.Cu" signal "BOTTOM")
		(9 "F.Adhes" user "F.Adhesive")
		(11 "B.Adhes" user "B.Adhesive")
		(13 "F.Paste" user "Package Geometry/Pastemask Top")
		(15 "B.Paste" user "Package Geometry/Pastemask Bottom")
		(5 "F.SilkS" user "Ref Des/Silkscreen Top")
		(7 "B.SilkS" user "Ref Des/Silkscreen Bottom")
		(1 "F.Mask" user "Board Geometry/Soldermask Top")
		(3 "B.Mask" user "Board Geometry/Soldermask Bottom")
		(17 "Dwgs.User" user "User.Drawings")
		(19 "Cmts.User" user "User.Comments")
		(21 "Eco1.User" user "User.Eco1")
		(23 "Eco2.User" user "User.Eco2")
		(25 "Edge.Cuts" user "Board Geometry/Outline")
		(27 "Margin" user)
		(31 "F.CrtYd" user "Package Geometry/Place Bound Top")
		(29 "B.CrtYd" user "Package Geometry/Place Bound Bottom")
		(35 "F.Fab" user "Ref Des/Assembly Top")
		(33 "B.Fab" user "Ref Des/Assembly Bottom")
	)
	(footprint ""
		(layer "F.Cu")
		(at 111.952024 -65.092072)
		(property "Reference" "U6003"
			(at -2.1082 -3.165348 0)
			(unlocked yes)
			(layer "F.SilkS")
			(effects
				(font
					(size 0.7874 0.5842)
					(thickness 0.1524)
				)
				(justify left)
			)
		)
		(property "Value" ""
			(at 0 0 0)
			(layer "F.Fab")
			(effects
				(font
					(size 1.27 1.27)
				)
			)
		)
		(duplicate_pad_numbers_are_jumpers no)
		(fp_line
			(start -1.8288 -2.500122)
			(end -1.8288 2.500122)
			(stroke
				(width 0.1524)
				(type default)
			)
			(layer "F.SilkS")
		)
		(fp_line
			(start -1.8288 2.500122)
			(end 1.8288 2.500122)
			(stroke
				(width 0.1524)
				(type default)
			)
			(layer "F.SilkS")
		)
		(fp_line
			(start -1.077722 -2.500122)
			(end -1.8288 -2.500122)
			(stroke
				(width 0.1524)
				(type default)
			)
			(layer "F.SilkS")
		)
		(fp_line
			(start 0 -1.4224)
			(end -1.077722 -2.500122)
			(stroke
				(width 0.1524)
				(type default)
			)
			(layer "F.SilkS")
		)
		(fp_line
			(start 1.077722 -2.500122)
			(end 0 -1.4224)
			(stroke
				(width 0.1524)
				(type default)
			)
			(layer "F.SilkS")
		)
		(fp_line
			(start 1.8288 -2.500122)
			(end 1.077722 -2.500122)
			(stroke
				(width 0.1524)
				(type default)
			)
			(layer "F.SilkS")
		)
		(fp_line
			(start 1.8288 2.500122)
			(end 1.8288 -2.500122)
			(stroke
				(width 0.1524)
				(type default)
			)
			(layer "F.SilkS")
		)
		(fp_poly
			(pts
				(xy -2.313178 -3.971798) (xy -3.329178 -3.971798) (xy -2.821178 -2.955798)
			)
			(stroke
				(width 0)
				(type default)
			)
			(fill yes)
			(layer "F.SilkS")
		)
		(fp_line
			(start -1.999996 -2.500122)
			(end -1.999996 2.500122)
			(stroke
				(width 0.1)
				(type default)
			)
			(layer "F.Fab")
		)
		(fp_line
			(start -1.999996 2.500122)
			(end 1.999996 2.500122)
			(stroke
				(width 0.1)
				(type default)
			)
			(layer "F.Fab")
		)
		(fp_line
			(start 1.999996 -2.500122)
			(end -1.999996 -2.500122)
			(stroke
				(width 0.1)
				(type default)
			)
			(layer "F.Fab")
		)
		(fp_line
			(start 1.999996 2.500122)
			(end 1.999996 -2.500122)
			(stroke
				(width 0.1)
				(type default)
			)
			(layer "F.Fab")
		)
		(fp_poly
			(pts
				(xy -4.5085 -2.413) (xy -4.5085 -1.397) (xy -3.4925 -1.905)
			)
			(stroke
				(width 0)
				(type default)
			)
			(fill yes)
			(layer "F.Fab")
		)
		(pad "1" smd rect
			(at -2.599944 -1.905 270)
			(size 0.889 1.27)
			(layers "F.Cu" "F.Mask" "F.Paste")
			(net "USB_CPU0_ADD_A0")
		)
		(pad "2" smd rect
			(at -2.599944 -0.635 270)
			(size 0.889 1.27)
			(layers "F.Cu" "F.Mask" "F.Paste")
			(net "USB_CPU0_ADD_A1")
		)
		(pad "3" smd rect
			(at -2.599944 0.635 270)
			(size 0.889 1.27)
			(layers "F.Cu" "F.Mask" "F.Paste")
			(net "USB_CPU0_ADD_A2")
		)
		(pad "4" smd rect
			(at -2.599944 1.905 270)
			(size 0.889 1.27)
			(layers "F.Cu" "F.Mask" "F.Paste")
			(net "GND")
		)
		(pad "5" smd rect
			(at 2.599944 1.905 270)
			(size 0.889 1.27)
			(layers "F.Cu" "F.Mask" "F.Paste")
			(net "SMB_USB_CPU0_HUB1_SDA_R2")
		)
		(pad "6" smd rect
			(at 2.599944 0.635 270)
			(size 0.889 1.27)
			(layers "F.Cu" "F.Mask" "F.Paste")
			(net "SMB_USB_CPU0_HUB1_SCL_R2")
		)
		(pad "7" smd rect
			(at 2.599944 -0.635 270)
			(size 0.889 1.27)
			(layers "F.Cu" "F.Mask" "F.Paste")
			(net "PD_USB_CPU0_WP")
		)
		(pad "8" smd rect
			(at 2.599944 -1.905 270)
			(size 0.889 1.27)
			(layers "F.Cu" "F.Mask" "F.Paste")
			(net "P3V3_AUX")
		)
	)
	(footprint ""
		(layer "F.Cu")
		(at 341.578184 -172.311822 180)
		(property "Reference" "PR294"
			(at 0 0 180)
			(layer "F.SilkS")
			(hide yes)
			(effects
				(font
					(size 1.27 1.27)
				)
			)
		)
		(property "Value" ""
			(at 0 0 180)
			(layer "F.Fab")
			(effects
				(font
					(size 1.27 1.27)
				)
			)
		)
		(duplicate_pad_numbers_are_jumpers no)
		(fp_line
			(start 0.7874 0.4064)
			(end -0.7874 0.4064)
			(stroke
				(width 0.1524)
				(type default)
			)
			(layer "F.SilkS")
		)
		(fp_line
			(start 0.7874 -0.4064)
			(end 0.7874 0.4064)
			(stroke
				(width 0.1524)
				(type default)
			)
			(layer "F.SilkS")
		)
		(fp_line
			(start -0.7874 0.4064)
			(end -0.7874 -0.4064)
			(stroke
				(width 0.1524)
				(type default)
			)
			(layer "F.SilkS")
		)
		(fp_line
			(start -0.7874 -0.4064)
			(end 0.7874 -0.4064)
			(stroke
				(width 0.1524)
				(type default)
			)
			(layer "F.SilkS")
		)
		(fp_line
			(start 0.67945 0.3048)
			(end 0.120396 0.3048)
			(stroke
				(width 0.1)
				(type default)
			)
			(layer "F.Fab")
		)
		(fp_line
			(start 0.67945 -0.3048)
			(end 0.67945 0.3048)
			(stroke
				(width 0.1)
				(type default)
			)
			(layer "F.Fab")
		)
		(fp_line
			(start 0.12065 -0.2794)
			(end 0.12065 -0.3048)
			(stroke
				(width 0.1)
				(type default)
			)
			(layer "F.Fab")
		)
		(fp_line
			(start 0.12065 -0.3048)
			(end 0.67945 -0.3048)
			(stroke
				(width 0.1)
				(type default)
			)
			(layer "F.Fab")
		)
		(fp_line
			(start 0.120396 0.3048)
			(end 0.120396 0.2794)
			(stroke
				(width 0.1)
				(type default)
			)
			(layer "F.Fab")
		)
		(fp_line
			(start 0.120396 0.2794)
			(end -0.12065 0.2794)
			(stroke
				(width 0.1)
				(type default)
			)
			(layer "F.Fab")
		)
		(fp_line
			(start -0.12065 0.3048)
			(end -0.67945 0.3048)
			(stroke
				(width 0.1)
				(type default)
			)
			(layer "F.Fab")
		)
		(fp_line
			(start -0.12065 0.2794)
			(end -0.12065 0.3048)
			(stroke
				(width 0.1)
				(type default)
			)
			(layer "F.Fab")
		)
		(fp_line
			(start -0.12065 -0.2794)
			(end 0.12065 -0.2794)
			(stroke
				(width 0.1)
				(type default)
			)
			(layer "F.Fab")
		)
		(fp_line
			(start -0.12065 -0.305054)
			(end -0.12065 -0.2794)
			(stroke
				(width 0.1)
				(type default)
			)
			(layer "F.Fab")
		)
		(fp_line
			(start -0.67945 0.3048)
			(end -0.67945 -0.305054)
			(stroke
				(width 0.1)
				(type default)
			)
			(layer "F.Fab")
		)
		(fp_line
			(start -0.67945 -0.305054)
			(end -0.12065 -0.305054)
			(stroke
				(width 0.1)
				(type default)
			)
			(layer "F.Fab")
		)
		(pad "1" smd circle
			(at -0.40005 0 180)
			(size 0 0)
			(layers "F.Cu" "F.Mask" "F.Paste")
			(net "PVDDCR_CPU0_P0")
		)
		(pad "2" smd circle
			(at 0.40005 0 180)
			(size 0 0)
			(layers "F.Cu" "F.Mask" "F.Paste")
			(net "VSENSE_PVDDCR_CPU0_P0_DP")
		)
	)
)
